(kicad_pcb
	(version 20240108)
	(generator "pcbnew")
	(generator_version "8.0")
	(general
		(thickness 1.62)
		(legacy_teardrops no)
	)
	(paper "A4")
	(title_block
		(title "Jetson Orin Baseboard")
		(date "2025-03-12")
		(rev "1.3.4")
		(company "Antmicro Ltd")
		(comment 1 "www.antmicro.com")
		(comment 9 "footprints 468-470 of 677")
	)
	(layers
		(0 "F.Cu" signal)
		(1 "In1.Cu" signal)
		(2 "In2.Cu" signal)
		(3 "In3.Cu" signal)
		(4 "In4.Cu" jumper)
		(5 "In5.Cu" signal)
		(6 "In6.Cu" signal)
		(31 "B.Cu" signal)
		(32 "B.Adhes" user "B.Adhesive")
		(33 "F.Adhes" user "F.Adhesive")
		(34 "B.Paste" user)
		(35 "F.Paste" user)
		(36 "B.SilkS" user "B.Silkscreen")
		(37 "F.SilkS" user "F.Silkscreen")
		(38 "B.Mask" user)
		(39 "F.Mask" user)
		(40 "Dwgs.User" user "User.Drawings")
		(41 "Cmts.User" user "User.Comments")
		(42 "Eco1.User" user "User.Eco1")
		(43 "Eco2.User" user "User.Eco2")
		(44 "Edge.Cuts" user)
		(45 "Margin" user)
		(46 "B.CrtYd" user "B.Courtyard")
		(47 "F.CrtYd" user "F.Courtyard")
		(48 "B.Fab" user)
		(49 "F.Fab" user)
	)
	(footprint "antmicro-footprints:Spacer_Drill3.7mm_H6.5mm_9774065151R"
		(locked yes)
		(layer "B.Cu")
		(at 144.75 72.25 180)
		(descr "Spacer M=3 h=6.5mm fi=5.1mm")
		(property "Reference" "H5"
			(at 2.25 -3.05 0)
			(layer "B.SilkS")
			(effects
				(font
					(size 0.7 0.7)
					(thickness 0.15)
				)
				(justify left bottom mirror)
			)
		)
		(property "Value" "Spacer_Drill3.7mm_H6.5mm_9774065151R"
			(at 0 -4 0)
			(layer "B.Fab")
			(effects
				(font
					(size 0.7 0.7)
					(thickness 0.15)
				)
				(justify left bottom mirror)
			)
		)
		(property "Footprint" "antmicro-footprints:Spacer_Drill3.7mm_H6.5mm_9774065151R"
			(at 0 0 180)
			(layer "F.Fab")
			(hide yes)
			(effects
				(font
					(size 1.27 1.27)
					(thickness 0.15)
				)
			)
		)
		(property "Datasheet" "https://www.we-online.com/components/products/datasheet/9774065151R.pdf"
			(at 0 0 180)
			(layer "F.Fab")
			(hide yes)
			(effects
				(font
					(size 1.27 1.27)
					(thickness 0.15)
				)
			)
		)
		(property "Author" "Antmicro"
			(at 289.5 144.5 0)
			(layer "B.Fab")
			(hide yes)
			(effects
				(font
					(size 1 1)
					(thickness 0.15)
				)
				(justify mirror)
			)
		)
		(property "License" "Apache-2.0"
			(at 289.5 144.5 0)
			(layer "B.Fab")
			(hide yes)
			(effects
				(font
					(size 1 1)
					(thickness 0.15)
				)
				(justify mirror)
			)
		)
		(property "MPN" "9774065151R"
			(at 289.5 144.5 0)
			(layer "B.Fab")
			(hide yes)
			(effects
				(font
					(size 1 1)
					(thickness 0.15)
				)
				(justify mirror)
			)
		)
		(property "Manufacturer" "Würth Elektronik"
			(at 289.5 144.5 0)
			(layer "B.Fab")
			(hide yes)
			(effects
				(font
					(size 1 1)
					(thickness 0.15)
				)
				(justify mirror)
			)
		)
		(sheetname "Root")
		(sheetfile "jetson-orin-baseboard.kicad_sch")
		(solder_paste_ratio -1)
		(attr smd)
		(fp_circle
			(center 0 0)
			(end 3.05 0)
			(stroke
				(width 0.05)
				(type solid)
			)
			(fill none)
			(layer "B.CrtYd")
		)
		(fp_circle
			(center 0 0)
			(end 2.6 0)
			(stroke
				(width 0.15)
				(type solid)
			)
			(fill none)
			(layer "B.Fab")
		)
		(fp_text user "${REFERENCE}"
			(at -9.6 -6.5 0)
			(layer "B.Fab")
			(hide yes)
			(effects
				(font
					(size 0.7 0.7)
					(thickness 0.15)
				)
				(justify left bottom mirror)
			)
		)
		(fp_text user "Author: Antmicro"
			(at -9.6 -7.7 0)
			(layer "B.Fab")
			(hide yes)
			(effects
				(font
					(size 0.7 0.7)
					(thickness 0.15)
				)
				(justify left bottom mirror)
			)
		)
		(fp_text user "License: Apache-2.0"
			(at -9.6 -8.9 0)
			(layer "B.Fab")
			(hide yes)
			(effects
				(font
					(size 0.7 0.7)
					(thickness 0.15)
				)
				(justify left bottom mirror)
			)
		)
		(pad "" smd custom
			(at -1.7 -1.7 90)
			(size 0.62 0.62)
			(layers "B.Paste")
			(thermal_bridge_angle 90)
			(options
				(clearance outline)
				(anchor circle)
			)
			(primitives
				(gr_arc
					(start 1.266786 0.24747)
					(mid 0.285453 -0.29439)
					(end -0.250195 -1.279127)
					(width 0.2)
				)
				(gr_arc
					(start 1.259603 0.339191)
					(mid 0.218448 -0.232561)
					(end -0.34334 -1.279127)
					(width 0.2)
				)
				(gr_arc
					(start 1.255279 0.431435)
					(mid 0.152481 -0.169693)
					(end -0.436309 -1.279127)
					(width 0.2)
				)
				(gr_arc
					(start 1.253811 0.524161)
					(mid 0.087542 -0.105784)
					(end -0.529126 -1.279127)
					(width 0.2)
				)
				(gr_arc
					(start 1.275473 0.621136)
					(mid 0.0309 -0.033527)
					(end -0.621807 -1.279127)
					(width 0.2)
				)
				(gr_arc
					(start 1.263664 0.711602)
					(mid -0.037759 0.026651)
					(end -0.71437 -1.279127)
					(width 0.2)
				)
				(gr_arc
					(start 1.253435 0.802342)
					(mid -0.105837 0.087395)
					(end -0.806826 -1.279127)
					(width 0.2)
				)
				(gr_arc
					(start 1.267475 0.897258)
					(mid -0.165236 0.156885)
					(end -0.899187 -1.279127)
					(width 0.2)
				)
				(gr_arc
					(start 1.270645 0.990112)
					(mid -0.228522 0.222449)
					(end -0.991463 -1.279127)
					(width 0.2)
				)
				(gr_arc
					(start 1.266278 1.081674)
					(mid -0.294507 0.285313)
					(end -1.083663 -1.279127)
					(width 0.2)
				)
				(gr_line
					(start 1.279127 1.083663)
					(end 1.279127 0.250195)
					(width 0.2)
				)
				(gr_line
					(start -1.083663 -1.279127)
					(end -0.250195 -1.279127)
					(width 0.2)
				)
			)
		)
		(pad "" smd custom
			(at -1.7 1.7 180)
			(size 0.62 0.62)
			(layers "B.Paste")
			(thermal_bridge_angle 90)
			(options
				(clearance outline)
				(anchor circle)
			)
			(primitives
				(gr_arc
					(start 1.266786 0.24747)
					(mid 0.285453 -0.29439)
					(end -0.250195 -1.279127)
					(width 0.2)
				)
				(gr_arc
					(start 1.259603 0.339191)
					(mid 0.218448 -0.232561)
					(end -0.34334 -1.279127)
					(width 0.2)
				)
				(gr_arc
					(start 1.255279 0.431435)
					(mid 0.152481 -0.169693)
					(end -0.436309 -1.279127)
					(width 0.2)
				)
				(gr_arc
					(start 1.253811 0.524161)
					(mid 0.087542 -0.105784)
					(end -0.529126 -1.279127)
					(width 0.2)
				)
				(gr_arc
					(start 1.275473 0.621136)
					(mid 0.0309 -0.033527)
					(end -0.621807 -1.279127)
					(width 0.2)
				)
				(gr_arc
					(start 1.263664 0.711602)
					(mid -0.037759 0.026651)
					(end -0.71437 -1.279127)
					(width 0.2)
				)
				(gr_arc
					(start 1.253435 0.802342)
					(mid -0.105837 0.087395)
					(end -0.806826 -1.279127)
					(width 0.2)
				)
				(gr_arc
					(start 1.267475 0.897258)
					(mid -0.165236 0.156885)
					(end -0.899187 -1.279127)
					(width 0.2)
				)
				(gr_arc
					(start 1.270645 0.990112)
					(mid -0.228522 0.222449)
					(end -0.991463 -1.279127)
					(width 0.2)
				)
				(gr_arc
					(start 1.266278 1.081674)
					(mid -0.294507 0.285313)
					(end -1.083663 -1.279127)
					(width 0.2)
				)
				(gr_line
					(start 1.279127 1.083663)
					(end 1.279127 0.250195)
					(width 0.2)
				)
				(gr_line
					(start -1.083663 -1.279127)
					(end -0.250195 -1.279127)
					(width 0.2)
				)
			)
		)
		(pad "" smd custom
			(at 1.7 -1.7)
			(size 0.62 0.62)
			(layers "B.Paste")
			(thermal_bridge_angle 90)
			(options
				(clearance outline)
				(anchor circle)
			)
			(primitives
				(gr_arc
					(start 1.266786 0.24747)
					(mid 0.285453 -0.29439)
					(end -0.250195 -1.279127)
					(width 0.2)
				)
				(gr_arc
					(start 1.259603 0.339191)
					(mid 0.218448 -0.232561)
					(end -0.34334 -1.279127)
					(width 0.2)
				)
				(gr_arc
					(start 1.255279 0.431435)
					(mid 0.152481 -0.169693)
					(end -0.436309 -1.279127)
					(width 0.2)
				)
				(gr_arc
					(start 1.253811 0.524161)
					(mid 0.087542 -0.105784)
					(end -0.529126 -1.279127)
					(width 0.2)
				)
				(gr_arc
					(start 1.275473 0.621136)
					(mid 0.0309 -0.033527)
					(end -0.621807 -1.279127)
					(width 0.2)
				)
				(gr_arc
					(start 1.263664 0.711602)
					(mid -0.037759 0.026651)
					(end -0.71437 -1.279127)
					(width 0.2)
				)
				(gr_arc
					(start 1.253435 0.802342)
					(mid -0.105837 0.087395)
					(end -0.806826 -1.279127)
					(width 0.2)
				)
				(gr_arc
					(start 1.267475 0.897258)
					(mid -0.165236 0.156885)
					(end -0.899187 -1.279127)
					(width 0.2)
				)
				(gr_arc
					(start 1.270645 0.990112)
					(mid -0.228522 0.222449)
					(end -0.991463 -1.279127)
					(width 0.2)
				)
				(gr_arc
					(start 1.266278 1.081674)
					(mid -0.294507 0.285313)
					(end -1.083663 -1.279127)
					(width 0.2)
				)
				(gr_line
					(start 1.279127 1.083663)
					(end 1.279127 0.250195)
					(width 0.2)
				)
				(gr_line
					(start -1.083663 -1.279127)
					(end -0.250195 -1.279127)
					(width 0.2)
				)
			)
		)
		(pad "" smd custom
			(at 1.7 1.7 270)
			(size 0.62 0.62)
			(layers "B.Paste")
			(thermal_bridge_angle 90)
			(options
				(clearance outline)
				(anchor circle)
			)
			(primitives
				(gr_arc
					(start 1.266786 0.24747)
					(mid 0.285453 -0.29439)
					(end -0.250195 -1.279127)
					(width 0.2)
				)
				(gr_arc
					(start 1.259603 0.339191)
					(mid 0.218448 -0.232561)
					(end -0.34334 -1.279127)
					(width 0.2)
				)
				(gr_arc
					(start 1.255279 0.431435)
					(mid 0.152481 -0.169693)
					(end -0.436309 -1.279127)
					(width 0.2)
				)
				(gr_arc
					(start 1.253811 0.524161)
					(mid 0.087542 -0.105784)
					(end -0.529126 -1.279127)
					(width 0.2)
				)
				(gr_arc
					(start 1.275473 0.621136)
					(mid 0.0309 -0.033527)
					(end -0.621807 -1.279127)
					(width 0.2)
				)
				(gr_arc
					(start 1.263664 0.711602)
					(mid -0.037759 0.026651)
					(end -0.71437 -1.279127)
					(width 0.2)
				)
				(gr_arc
					(start 1.253435 0.802342)
					(mid -0.105837 0.087395)
					(end -0.806826 -1.279127)
					(width 0.2)
				)
				(gr_arc
					(start 1.267475 0.897258)
					(mid -0.165236 0.156885)
					(end -0.899187 -1.279127)
					(width 0.2)
				)
				(gr_arc
					(start 1.270645 0.990112)
					(mid -0.228522 0.222449)
					(end -0.991463 -1.279127)
					(width 0.2)
				)
				(gr_arc
					(start 1.266278 1.081674)
					(mid -0.294507 0.285313)
					(end -1.083663 -1.279127)
					(width 0.2)
				)
				(gr_line
					(start 1.279127 1.083663)
					(end 1.279127 0.250195)
					(width 0.2)
				)
				(gr_line
					(start -1.083663 -1.279127)
					(end -0.250195 -1.279127)
					(width 0.2)
				)
			)
		)
		(pad "1" thru_hole circle
			(at 0 0 180)
			(size 6 6)
			(drill 3.7)
			(layers "*.Cu" "*.Mask")
			(remove_unused_layers no)
			(net 1 "GND")
			(pintype "passive")
		)
	)
	(footprint "antmicro-footprints:R_0402_1005Metric"
		(layer "B.Cu")
		(at 53.23 78.61 90)
		(descr "Resistor SMD 0402")
		(tags "resistor SMD 0402")
		(property "Reference" "R274"
			(at -7.69 21.07 90)
			(layer "B.SilkS")
			(effects
				(font
					(size 0.7 0.7)
					(thickness 0.15)
				)
				(justify left top mirror)
			)
		)
		(property "Value" "R_100k_0402"
			(at -1.011843 -1.772046 90)
			(layer "B.Fab")
			(effects
				(font
					(size 0.7 0.7)
					(thickness 0.15)
				)
				(justify right top mirror)
			)
		)
		(property "Footprint" "antmicro-footprints:R_0402_1005Metric"
			(at 0 0 90)
			(layer "B.Fab")
			(hide yes)
			(effects
				(font
					(size 1.27 1.27)
					(thickness 0.15)
				)
				(justify mirror)
			)
		)
		(property "Datasheet" "https://www.bourns.com/docs/product-datasheets/cr.pdf"
			(at 0 0 90)
			(layer "B.Fab")
			(hide yes)
			(effects
				(font
					(size 1.27 1.27)
					(thickness 0.15)
				)
				(justify mirror)
			)
		)
		(property "MPN" "CR0402-FX-1003GLF"
			(at 0 0 -90)
			(unlocked yes)
			(layer "B.Fab")
			(hide yes)
			(effects
				(font
					(size 1 1)
					(thickness 0.15)
				)
				(justify mirror)
			)
		)
		(property "Manufacturer" "Bourns"
			(at 0 0 -90)
			(unlocked yes)
			(layer "B.Fab")
			(hide yes)
			(effects
				(font
					(size 1 1)
					(thickness 0.15)
				)
				(justify mirror)
			)
		)
		(property "License" "Apache-2.0"
			(at 0 0 -90)
			(unlocked yes)
			(layer "B.Fab")
			(hide yes)
			(effects
				(font
					(size 1 1)
					(thickness 0.15)
				)
				(justify mirror)
			)
		)
		(property "Author" "Antmicro"
			(at 0 0 -90)
			(unlocked yes)
			(layer "B.Fab")
			(hide yes)
			(effects
				(font
					(size 1 1)
					(thickness 0.15)
				)
				(justify mirror)
			)
		)
		(property "Val" "100k"
			(at 0 0 -90)
			(unlocked yes)
			(layer "B.Fab")
			(hide yes)
			(effects
				(font
					(size 1 1)
					(thickness 0.15)
				)
				(justify mirror)
			)
		)
		(property "Tolerance" "1%"
			(at 0 0 -90)
			(unlocked yes)
			(layer "B.Fab")
			(hide yes)
			(effects
				(font
					(size 1 1)
					(thickness 0.15)
				)
				(justify mirror)
			)
		)
		(sheetname "Supply")
		(sheetfile "supply.kicad_sch")
		(attr smd)
		(fp_poly
			(pts
				(xy -0.925 0.47) (xy -0.925 -0.47) (xy 0.925 -0.47) (xy 0.925 0.47)
			)
			(stroke
				(width 0.05)
				(type default)
			)
			(fill none)
			(layer "B.CrtYd")
		)
		(fp_poly
			(pts
				(xy -0.5 0.25) (xy -0.5 -0.25) (xy 0.5 -0.25) (xy 0.5 0.25)
			)
			(stroke
				(width 0.15)
				(type solid)
			)
			(fill none)
			(layer "B.Fab")
		)
		(fp_text user "Author: Antmicro"
			(at -0.95 -4.169 90)
			(layer "B.Fab")
			(hide yes)
			(effects
				(font
					(size 0.7 0.7)
					(thickness 0.15)
				)
				(justify right top mirror)
			)
		)
		(fp_text user "License: Apache-2.0"
			(at -0.949999 -5.169 90)
			(layer "B.Fab")
			(hide yes)
			(effects
				(font
					(size 0.7 0.7)
					(thickness 0.15)
				)
				(justify right top mirror)
			)
		)
		(fp_text user "${REFERENCE}"
			(at -0.95 -3.168 90)
			(layer "B.Fab")
			(hide yes)
			(effects
				(font
					(size 0.7 0.7)
					(thickness 0.15)
				)
				(justify right top mirror)
			)
		)
		(pad "1" smd roundrect
			(at -0.48 0 90)
			(size 0.59 0.64)
			(layers "B.Cu" "B.Paste" "B.Mask")
			(roundrect_rratio 0.25)
			(net 799 "/Supply/PG_{HP}")
			(pintype "passive")
		)
		(pad "2" smd roundrect
			(at 0.48 0 90)
			(size 0.59 0.64)
			(layers "B.Cu" "B.Paste" "B.Mask")
			(roundrect_rratio 0.25)
			(net 787 "+5V_SoM")
			(pintype "passive")
		)
	)
	(footprint "antmicro-footprints:R_0402_1005Metric"
		(layer "B.Cu")
		(at 42.2 119.3 90)
		(descr "Resistor SMD 0402")
		(tags "resistor SMD 0402")
		(property "Reference" "R151"
			(at 3.68 0.3 -90)
			(layer "B.SilkS")
			(effects
				(font
					(size 0.7 0.7)
					(thickness 0.15)
				)
				(justify left bottom mirror)
			)
		)
		(property "Value" "R_200R_0402"
			(at 0 -1.4 -90)
			(layer "B.Fab")
			(effects
				(font
					(size 0.7 0.7)
					(thickness 0.15)
				)
				(justify left bottom mirror)
			)
		)
		(property "Footprint" "antmicro-footprints:R_0402_1005Metric"
			(at 0 0 90)
			(layer "F.Fab")
			(hide yes)
			(effects
				(font
					(size 1.27 1.27)
					(thickness 0.15)
				)
			)
		)
		(property "Datasheet" "https://www.bourns.com/docs/product-datasheets/cr.pdf"
			(at 0 0 90)
			(layer "F.Fab")
			(hide yes)
			(effects
				(font
					(size 1.27 1.27)
					(thickness 0.15)
				)
			)
		)
		(property "Author" "Antmicro"
			(at 161.5 77.1 0)
			(layer "B.Fab")
			(hide yes)
			(effects
				(font
					(size 1 1)
					(thickness 0.15)
				)
				(justify mirror)
			)
		)
		(property "License" "Apache-2.0"
			(at 161.5 77.1 0)
			(layer "B.Fab")
			(hide yes)
			(effects
				(font
					(size 1 1)
					(thickness 0.15)
				)
				(justify mirror)
			)
		)
		(property "MPN" "CR0402-FX-2000GLF"
			(at 161.5 77.1 0)
			(layer "B.Fab")
			(hide yes)
			(effects
				(font
					(size 1 1)
					(thickness 0.15)
				)
				(justify mirror)
			)
		)
		(property "Manufacturer" "Bourns"
			(at 161.5 77.1 0)
			(layer "B.Fab")
			(hide yes)
			(effects
				(font
					(size 1 1)
					(thickness 0.15)
				)
				(justify mirror)
			)
		)
		(property "Tolerance" "1%"
			(at 161.5 77.1 0)
			(layer "B.Fab")
			(hide yes)
			(effects
				(font
					(size 1 1)
					(thickness 0.15)
				)
				(justify mirror)
			)
		)
		(property "Val" "200R"
			(at 161.5 77.1 0)
			(layer "B.Fab")
			(hide yes)
			(effects
				(font
					(size 1 1)
					(thickness 0.15)
				)
				(justify mirror)
			)
		)
		(sheetname "Ethernet")
		(sheetfile "ethernet.kicad_sch")
		(attr smd)
		(fp_rect
			(start -0.925 0.47)
			(end 0.925 -0.47)
			(stroke
				(width 0.05)
				(type default)
			)
			(fill none)
			(layer "B.CrtYd")
		)
		(fp_rect
			(start -0.5 0.25)
			(end 0.5 -0.25)
			(stroke
				(width 0.15)
				(type solid)
			)
			(fill none)
			(layer "B.Fab")
		)
		(fp_text user "${REFERENCE}"
			(at -0.95 -3.168 -90)
			(layer "B.Fab")
			(hide yes)
			(effects
				(font
					(size 0.7 0.7)
					(thickness 0.15)
				)
				(justify left bottom mirror)
			)
		)
		(fp_text user "License: Apache-2.0"
			(at -0.95 -5.169 -90)
			(layer "B.Fab")
			(hide yes)
			(effects
				(font
					(size 0.7 0.7)
					(thickness 0.15)
				)
				(justify left bottom mirror)
			)
		)
		(fp_text user "Author: Antmicro"
			(at -0.95 -4.169 -90)
			(layer "B.Fab")
			(hide yes)
			(effects
				(font
					(size 0.7 0.7)
					(thickness 0.15)
				)
				(justify left bottom mirror)
			)
		)
		(pad "1" smd roundrect
			(at -0.48 0 90)
			(size 0.59 0.64)
			(layers "B.Cu" "B.Paste" "B.Mask")
			(roundrect_rratio 0.25)
			(net 552 "Net-(J6-LED_YEL-)")
			(pintype "passive")
		)
		(pad "2" smd roundrect
			(at 0.48 0 90)
			(size 0.59 0.64)
			(layers "B.Cu" "B.Paste" "B.Mask")
			(roundrect_rratio 0.25)
			(net 459 "GBE_LED_ACT")
			(pintype "passive")
		)
	)
)
